(kicad_pcb
	(version 20221018)
	(generator pcbnew)
	(general
    (thickness 1.586)
  )
	(paper "A4")
	(title_block
    (date "2024-03-26")
    (rev "1.1.3")
		(comment 9 "footprints 93-100 of 146")
	)
	(layers
    (0 "F.Cu" signal)
    (1 "In1.Cu" power)
    (2 "In2.Cu" power)
    (31 "B.Cu" signal)
    (32 "B.Adhes" user "B.Adhesive")
    (33 "F.Adhes" user "F.Adhesive")
    (34 "B.Paste" user)
    (35 "F.Paste" user)
    (36 "B.SilkS" user "B.Silkscreen")
    (37 "F.SilkS" user "F.Silkscreen")
    (38 "B.Mask" user)
    (39 "F.Mask" user)
    (40 "Dwgs.User" user "User.Drawings")
    (41 "Cmts.User" user "User.Comments")
    (42 "Eco1.User" user "User.Eco1")
    (43 "Eco2.User" user "User.Eco2")
    (44 "Edge.Cuts" user)
    (45 "Margin" user)
    (46 "B.CrtYd" user "B.Courtyard")
    (47 "F.CrtYd" user "F.Courtyard")
    (48 "B.Fab" user)
    (49 "F.Fab" user)
  )
	(footprint "scalenode-cm4-baseboard-footprints:Spacer_Drill1mm_H4mm_97730406332R" (layer "B.Cu")
    (at 142.039 76.877)
    (property "Author" "Antmicro")
    (property "DNP" "DNP")
    (property "License" "Apache-2.0")
    (property "MPN" "97730406332R ")
    (property "Manufacturer" "Würth Elektronik")
    (property "Sheetfile" "nvme-ssd.kicad_sch")
    (property "Sheetname" "NVMe SSD")
    (property "dnp" "")
    (property "exclude_from_bom" "")
    (attr exclude_from_pos_files exclude_from_bom)
    (fp_text reference "SP1" (at 1.071 -2.127 unlocked) (layer "B.SilkS")
        (effects (font (size 0.7 0.7) (thickness 0.15)) (justify left bottom mirror))
    )
    (fp_text value "Spacer_Drill1mm_H4mm_97730406332R" (at 5.183069 1.377434 180 unlocked) (layer "B.Fab")
        (effects (font (size 0.7 0.7) (thickness 0.15)) (justify left bottom mirror))
    )
    (fp_text user "${REFERENCE}" (at 5.259356 -0.014823 180) (layer "B.Fab") hide
        (effects (font (size 0.7 0.7) (thickness 0.15)) (justify left bottom mirror))
    )
    (fp_text user "License: Apache-2.0" (at 5.259356 -2.414823 180) (layer "B.Fab") hide
        (effects (font (size 0.7 0.7) (thickness 0.15)) (justify left bottom mirror))
    )
    (fp_text user "Author: Antmicro" (at 5.259356 -1.214823 180) (layer "B.Fab") hide
        (effects (font (size 0.7 0.7) (thickness 0.15)) (justify left bottom mirror))
    )
    (fp_line (start -1.849 -0.569) (end -1.849 0.579)
      (stroke (width 0.12) (type solid)) (layer "B.Paste"))
    (fp_line (start -1.748 -0.819) (end -1.748 0.83)
      (stroke (width 0.12) (type solid)) (layer "B.Paste"))
    (fp_line (start -1.65 -0.998) (end -1.65 1.024)
      (stroke (width 0.12) (type solid)) (layer "B.Paste"))
    (fp_line (start -1.549 -1.149) (end -1.549 1.159)
      (stroke (width 0.12) (type solid)) (layer "B.Paste"))
    (fp_line (start -1.448 -1.274) (end -1.448 1.275)
      (stroke (width 0.12) (type solid)) (layer "B.Paste"))
    (fp_line (start -1.349 -1.375) (end -1.349 1.374)
      (stroke (width 0.12) (type solid)) (layer "B.Paste"))
    (fp_line (start -1.248 -1.476) (end -1.248 1.468)
      (stroke (width 0.12) (type solid)) (layer "B.Paste"))
    (fp_line (start -1.15 -1.551) (end -1.15 1.55)
      (stroke (width 0.12) (type solid)) (layer "B.Paste"))
    (fp_line (start -1.049 -1.625) (end -1.049 1.624)
      (stroke (width 0.12) (type solid)) (layer "B.Paste"))
    (fp_line (start -0.95 -1.676) (end -0.95 1.679)
      (stroke (width 0.12) (type solid)) (layer "B.Paste"))
    (fp_line (start -0.849 -1.726) (end -0.849 1.739)
      (stroke (width 0.12) (type solid)) (layer "B.Paste"))
    (fp_line (start -0.748 -1.774) (end -0.748 1.778)
      (stroke (width 0.12) (type solid)) (layer "B.Paste"))
    (fp_line (start -0.65 -1.825) (end -0.65 1.823)
      (stroke (width 0.12) (type solid)) (layer "B.Paste"))
    (fp_line (start -0.551 1.87) (end -0.551 -1.86)
      (stroke (width 0.12) (type solid)) (layer "B.Paste"))
    (fp_line (start 0.551 -1.87) (end 0.551 1.859)
      (stroke (width 0.12) (type solid)) (layer "B.Paste"))
    (fp_line (start 0.65 1.823) (end 0.65 -1.825)
      (stroke (width 0.12) (type solid)) (layer "B.Paste"))
    (fp_line (start 0.749 1.775) (end 0.749 -1.779)
      (stroke (width 0.12) (type solid)) (layer "B.Paste"))
    (fp_line (start 0.849 1.724) (end 0.849 -1.74)
      (stroke (width 0.12) (type solid)) (layer "B.Paste"))
    (fp_line (start 0.95 1.675) (end 0.95 -1.679)
      (stroke (width 0.12) (type solid)) (layer "B.Paste"))
    (fp_line (start 1.051 1.624) (end 1.051 -1.625)
      (stroke (width 0.12) (type solid)) (layer "B.Paste"))
    (fp_line (start 1.149 1.55) (end 1.149 -1.551)
      (stroke (width 0.12) (type solid)) (layer "B.Paste"))
    (fp_line (start 1.25 1.474) (end 1.25 -1.469)
      (stroke (width 0.12) (type solid)) (layer "B.Paste"))
    (fp_line (start 1.351 1.374) (end 1.351 -1.375)
      (stroke (width 0.12) (type solid)) (layer "B.Paste"))
    (fp_line (start 1.45 1.275) (end 1.45 -1.274)
      (stroke (width 0.12) (type solid)) (layer "B.Paste"))
    (fp_line (start 1.551 1.15) (end 1.551 -1.16)
      (stroke (width 0.12) (type solid)) (layer "B.Paste"))
    (fp_line (start 1.649 0.999) (end 1.649 -1.024)
      (stroke (width 0.12) (type solid)) (layer "B.Paste"))
    (fp_line (start 1.75 0.82) (end 1.75 -0.83)
      (stroke (width 0.12) (type solid)) (layer "B.Paste"))
    (fp_line (start 1.851 0.57) (end 1.851 -0.578)
      (stroke (width 0.12) (type solid)) (layer "B.Paste"))
    (fp_arc (start -0.551 1.874) (mid -1.952999 0.00274) (end -0.557 -1.873)
      (stroke (width 0.1) (type solid)) (layer "B.Paste"))
    (fp_arc (start 0.551 -1.875) (mid 1.953999 -0.002741) (end 0.557 1.874)
      (stroke (width 0.1) (type solid)) (layer "B.Paste"))
    (fp_circle (center 0.001 2.2) (end 0.051 2.2)
      (stroke (width 0.15) (type solid)) (fill solid) (layer "B.SilkS"))
    (fp_rect (start -1.9 1.9) (end 1.89 -1.89)
      (stroke (width 0.05) (type solid)) (fill none) (layer "B.CrtYd"))
    (pad "1" thru_hole custom (at 0.001 0) (size 4 4) (drill 1) (layers "B.Cu" "B.Mask")
      (net 216 "unconnected-(SP1-Pad1)") (pinfunction "1") (pintype "passive+no_connect") (solder_paste_margin -1.2) (zone_connect 0)
      (options (clearance outline) (anchor circle))
      (primitives
      ))
  )
	(footprint "scalenode-cm4-baseboard-footprints:R_0402_1005Metric" (layer "B.Cu")
    (at 131.5 83.8 180)
    (descr "Resistor SMD 0402")
    (tags "resistor SMD 0402")
    (property "Author" "Antmicro")
    (property "License" "Apache-2.0")
    (property "MPN" "CR0402-FX-1002GLF")
    (property "Manufacturer" "Bourns")
    (property "Sheetfile" "supply.kicad_sch")
    (property "Sheetname" "Supply")
    (property "Tolerance" "1%")
    (property "Val" "10k")
    (property "ki_description" "10k resistor in 0402 package with 1% tolerance")
    (attr smd)
    (fp_text reference "R19" (at -1.025 0.7) (layer "B.SilkS")
        (effects (font (size 0.7 0.7) (thickness 0.15)) (justify left bottom mirror))
    )
    (fp_text value "R_10k_0402" (at 0 -1.4) (layer "B.Fab")
        (effects (font (size 0.7 0.7) (thickness 0.15)) (justify left bottom mirror))
    )
    (fp_text user "Author: Antmicro" (at -0.95 -4.169) (layer "B.Fab") hide
        (effects (font (size 0.7 0.7) (thickness 0.15)) (justify left bottom mirror))
    )
    (fp_text user "${REFERENCE}" (at -0.95 -3.168) (layer "B.Fab") hide
        (effects (font (size 0.7 0.7) (thickness 0.15)) (justify left bottom mirror))
    )
    (fp_text user "License: Apache-2.0" (at -0.95 -5.169) (layer "B.Fab") hide
        (effects (font (size 0.7 0.7) (thickness 0.15)) (justify left bottom mirror))
    )
    (fp_rect (start -0.95 0.48) (end 0.95 -0.48)
      (stroke (width 0.05) (type solid)) (fill none) (layer "B.CrtYd"))
    (fp_rect (start -0.5 0.25) (end 0.5 -0.25)
      (stroke (width 0.15) (type solid)) (fill none) (layer "B.Fab"))
    (pad "1" smd roundrect (at -0.485 0 180) (size 0.59 0.64) (layers "B.Cu" "B.Paste" "B.Mask") (roundrect_rratio 0.25)
      (net 11 "GND") (pintype "passive"))
    (pad "2" smd roundrect (at 0.485 0 180) (size 0.59 0.64) (layers "B.Cu" "B.Paste" "B.Mask") (roundrect_rratio 0.25)
      (net 252 "Net-(U2-FB)") (pintype "passive"))
  )
	(footprint "scalenode-cm4-baseboard-footprints:R_0402_1005Metric" (layer "B.Cu")
    (at 88.425 89.156 -90)
    (descr "Resistor SMD 0402")
    (tags "resistor SMD 0402")
    (property "Author" "Antmicro")
    (property "License" "Apache-2.0")
    (property "MPN" "CR0402-FX-3300GLF")
    (property "Manufacturer" "Bourns")
    (property "Sheetfile" "interfaces.kicad_sch")
    (property "Sheetname" "Interfaces")
    (property "Tolerance" "1%")
    (property "Val" "330R")
    (property "ki_description" "330R resistor in 0402 package with 1% tolerance")
    (attr smd)
    (fp_text reference "R6" (at -2.506 -0.4 90) (layer "B.SilkS")
        (effects (font (size 0.7 0.7) (thickness 0.15)) (justify left bottom mirror))
    )
    (fp_text value "R_330R_0402" (at 0 -1.4 90) (layer "B.Fab")
        (effects (font (size 0.7 0.7) (thickness 0.15)) (justify left bottom mirror))
    )
    (fp_text user "License: Apache-2.0" (at -0.95 -5.169 90) (layer "B.Fab") hide
        (effects (font (size 0.7 0.7) (thickness 0.15)) (justify left bottom mirror))
    )
    (fp_text user "Author: Antmicro" (at -0.95 -4.169 90) (layer "B.Fab") hide
        (effects (font (size 0.7 0.7) (thickness 0.15)) (justify left bottom mirror))
    )
    (fp_text user "${REFERENCE}" (at -0.95 -3.168 90) (layer "B.Fab") hide
        (effects (font (size 0.7 0.7) (thickness 0.15)) (justify left bottom mirror))
    )
    (fp_rect (start -0.95 0.48) (end 0.95 -0.48)
      (stroke (width 0.05) (type solid)) (fill none) (layer "B.CrtYd"))
    (fp_rect (start -0.5 0.25) (end 0.5 -0.25)
      (stroke (width 0.15) (type solid)) (fill none) (layer "B.Fab"))
    (pad "1" smd roundrect (at -0.485 0 270) (size 0.59 0.64) (layers "B.Cu" "B.Paste" "B.Mask") (roundrect_rratio 0.25)
      (net 57 "GPIO3") (pintype "passive"))
    (pad "2" smd roundrect (at 0.485 0 270) (size 0.59 0.64) (layers "B.Cu" "B.Paste" "B.Mask") (roundrect_rratio 0.25)
      (net 201 "Net-(J4-CD1)") (pintype "passive"))
  )
	(footprint "scalenode-cm4-baseboard-footprints:C_0603_1608Metric" (layer "B.Cu")
    (at 173.022 67.352 -90)
    (descr "Capacitor SMD 0603")
    (tags "capacitor 0603")
    (property "Author" "Antmicro")
    (property "License" "Apache-2.0")
    (property "MPN" "GRM188R61A106KE69D")
    (property "Manufacturer" "Murata")
    (property "Sheetfile" "nvme-ssd.kicad_sch")
    (property "Sheetname" "NVMe SSD")
    (property "Val" "10u")
    (property "Voltage" "")
    (property "ki_description" " ")
    (attr smd)
    (fp_text reference "C1" (at -3.143667 -0.678 90) (layer "B.SilkS")
        (effects (font (size 0.7 0.7) (thickness 0.15)) (justify left bottom mirror))
    )
    (fp_text value "C_10u_0603" (at 0 -1.6 90) (layer "B.Fab")
        (effects (font (size 0.7 0.7) (thickness 0.15)) (justify left bottom mirror))
    )
    (fp_text user "Author: Antmicro" (at -1.682 -4.894 90) (layer "B.Fab") hide
        (effects (font (size 0.7 0.7) (thickness 0.15)) (justify left bottom mirror))
    )
    (fp_text user "License: Apache-2.0" (at -1.682 -5.895 90) (layer "B.Fab") hide
        (effects (font (size 0.7 0.7) (thickness 0.15)) (justify left bottom mirror))
    )
    (fp_text user "${REFERENCE}" (at -1.682 -3.895 90) (layer "B.Fab") hide
        (effects (font (size 0.7 0.7) (thickness 0.15)) (justify left bottom mirror))
    )
    (fp_line (start -0.3 -0.3) (end 0.3 -0.3)
      (stroke (width 0.15) (type solid)) (layer "B.SilkS"))
    (fp_line (start -0.3 0.3) (end 0.3 0.3)
      (stroke (width 0.15) (type solid)) (layer "B.SilkS"))
    (fp_rect (start -1.24 0.7) (end 1.24 -0.7)
      (stroke (width 0.05) (type solid)) (fill none) (layer "B.CrtYd"))
    (fp_rect (start -0.8 0.4) (end 0.8 -0.4)
      (stroke (width 0.15) (type solid)) (fill none) (layer "B.Fab"))
    (pad "1" smd roundrect (at -0.7 0 270) (size 0.6 0.8) (layers "B.Cu" "B.Paste" "B.Mask") (roundrect_rratio 0.2)
      (net 11 "GND") (pintype "passive"))
    (pad "2" smd roundrect (at 0.7 0 270) (size 0.6 0.8) (layers "B.Cu" "B.Paste" "B.Mask") (roundrect_rratio 0.2)
      (net 170 "3V3_SSD") (pintype "passive"))
  )
	(footprint "scalenode-cm4-baseboard-footprints:C_0603_1608Metric" (layer "B.Cu")
    (at 174.546 67.352 -90)
    (descr "Capacitor SMD 0603")
    (tags "capacitor 0603")
    (property "Author" "Antmicro")
    (property "Dielectric" "")
    (property "License" "Apache-2.0")
    (property "MPN" "0603YD105KAT2A")
    (property "Manufacturer" "Walsin")
    (property "Sheetfile" "nvme-ssd.kicad_sch")
    (property "Sheetname" "NVMe SSD")
    (property "Val" "1u")
    (property "Voltage" "")
    (property "ki_description" " ")
    (attr smd)
    (fp_text reference "C4" (at -3.143667 -0.504 90) (layer "B.SilkS")
        (effects (font (size 0.7 0.7) (thickness 0.15)) (justify left bottom mirror))
    )
    (fp_text value "C_1u_0603" (at 0 -1.6 90) (layer "B.Fab")
        (effects (font (size 0.7 0.7) (thickness 0.15)) (justify left bottom mirror))
    )
    (fp_text user "License: Apache-2.0" (at -1.682 -5.895 90) (layer "B.Fab") hide
        (effects (font (size 0.7 0.7) (thickness 0.15)) (justify left bottom mirror))
    )
    (fp_text user "Author: Antmicro" (at -1.682 -4.894 90) (layer "B.Fab") hide
        (effects (font (size 0.7 0.7) (thickness 0.15)) (justify left bottom mirror))
    )
    (fp_text user "${REFERENCE}" (at -1.682 -3.895 90) (layer "B.Fab") hide
        (effects (font (size 0.7 0.7) (thickness 0.15)) (justify left bottom mirror))
    )
    (fp_line (start -0.3 -0.3) (end 0.3 -0.3)
      (stroke (width 0.15) (type solid)) (layer "B.SilkS"))
    (fp_line (start -0.3 0.3) (end 0.3 0.3)
      (stroke (width 0.15) (type solid)) (layer "B.SilkS"))
    (fp_rect (start -1.24 0.7) (end 1.24 -0.7)
      (stroke (width 0.05) (type solid)) (fill none) (layer "B.CrtYd"))
    (fp_rect (start -0.8 0.4) (end 0.8 -0.4)
      (stroke (width 0.15) (type solid)) (fill none) (layer "B.Fab"))
    (pad "1" smd roundrect (at -0.7 0 270) (size 0.6 0.8) (layers "B.Cu" "B.Paste" "B.Mask") (roundrect_rratio 0.2)
      (net 11 "GND") (pintype "passive"))
    (pad "2" smd roundrect (at 0.7 0 270) (size 0.6 0.8) (layers "B.Cu" "B.Paste" "B.Mask") (roundrect_rratio 0.2)
      (net 170 "3V3_SSD") (pintype "passive"))
  )
	(footprint "scalenode-cm4-baseboard-footprints:C_0603_1608Metric" (layer "B.Cu")
    (at 176.07 86.148 90)
    (descr "Capacitor SMD 0603")
    (tags "capacitor 0603")
    (property "Author" "Antmicro")
    (property "Dielectric" "")
    (property "License" "Apache-2.0")
    (property "MPN" "0603YC104KAZ2A")
    (property "Manufacturer" "AVX")
    (property "Sheetfile" "nvme-ssd.kicad_sch")
    (property "Sheetname" "NVMe SSD")
    (property "Val" "100n")
    (property "Voltage" "")
    (property "ki_description" " ")
    (attr smd)
    (fp_text reference "C9" (at -3.168667 0.405 90) (layer "B.SilkS")
        (effects (font (size 0.7 0.7) (thickness 0.15)) (justify right bottom mirror))
    )
    (fp_text value "C_100n_0603" (at 0 -1.6 90) (layer "B.Fab")
        (effects (font (size 0.7 0.7) (thickness 0.15)) (justify right bottom mirror))
    )
    (fp_text user "${REFERENCE}" (at -1.682 -3.895 90) (layer "B.Fab") hide
        (effects (font (size 0.7 0.7) (thickness 0.15)) (justify right bottom mirror))
    )
    (fp_text user "Author: Antmicro" (at -1.682 -4.894 90) (layer "B.Fab") hide
        (effects (font (size 0.7 0.7) (thickness 0.15)) (justify right bottom mirror))
    )
    (fp_text user "License: Apache-2.0" (at -1.682 -5.895 90) (layer "B.Fab") hide
        (effects (font (size 0.7 0.7) (thickness 0.15)) (justify right bottom mirror))
    )
    (fp_line (start -0.3 -0.3) (end 0.3 -0.3)
      (stroke (width 0.15) (type solid)) (layer "B.SilkS"))
    (fp_line (start -0.3 0.3) (end 0.3 0.3)
      (stroke (width 0.15) (type solid)) (layer "B.SilkS"))
    (fp_rect (start -1.24 0.7) (end 1.24 -0.7)
      (stroke (width 0.05) (type solid)) (fill none) (layer "B.CrtYd"))
    (fp_rect (start -0.8 0.4) (end 0.8 -0.4)
      (stroke (width 0.15) (type solid)) (fill none) (layer "B.Fab"))
    (pad "1" smd roundrect (at -0.7 0 90) (size 0.6 0.8) (layers "B.Cu" "B.Paste" "B.Mask") (roundrect_rratio 0.2)
      (net 11 "GND") (pintype "passive"))
    (pad "2" smd roundrect (at 0.7 0 90) (size 0.6 0.8) (layers "B.Cu" "B.Paste" "B.Mask") (roundrect_rratio 0.2)
      (net 170 "3V3_SSD") (pintype "passive"))
  )
	(footprint "scalenode-cm4-baseboard-footprints:C_0603_1608Metric" (layer "B.Cu")
    (at 174.546 86.148 90)
    (descr "Capacitor SMD 0603")
    (tags "capacitor 0603")
    (property "Author" "Antmicro")
    (property "Dielectric" "")
    (property "License" "Apache-2.0")
    (property "MPN" "0603YD105KAT2A")
    (property "Manufacturer" "Walsin")
    (property "Sheetfile" "nvme-ssd.kicad_sch")
    (property "Sheetname" "NVMe SSD")
    (property "Val" "1u")
    (property "Voltage" "")
    (property "ki_description" " ")
    (attr smd)
    (fp_text reference "C6" (at -3.168667 0.429 90) (layer "B.SilkS")
        (effects (font (size 0.7 0.7) (thickness 0.15)) (justify right bottom mirror))
    )
    (fp_text value "C_1u_0603" (at 0 -1.6 90) (layer "B.Fab")
        (effects (font (size 0.7 0.7) (thickness 0.15)) (justify right bottom mirror))
    )
    (fp_text user "License: Apache-2.0" (at -1.682 -5.895 90) (layer "B.Fab") hide
        (effects (font (size 0.7 0.7) (thickness 0.15)) (justify right bottom mirror))
    )
    (fp_text user "Author: Antmicro" (at -1.682 -4.894 90) (layer "B.Fab") hide
        (effects (font (size 0.7 0.7) (thickness 0.15)) (justify right bottom mirror))
    )
    (fp_text user "${REFERENCE}" (at -1.682 -3.895 90) (layer "B.Fab") hide
        (effects (font (size 0.7 0.7) (thickness 0.15)) (justify right bottom mirror))
    )
    (fp_line (start -0.3 -0.3) (end 0.3 -0.3)
      (stroke (width 0.15) (type solid)) (layer "B.SilkS"))
    (fp_line (start -0.3 0.3) (end 0.3 0.3)
      (stroke (width 0.15) (type solid)) (layer "B.SilkS"))
    (fp_rect (start -1.24 0.7) (end 1.24 -0.7)
      (stroke (width 0.05) (type solid)) (fill none) (layer "B.CrtYd"))
    (fp_rect (start -0.8 0.4) (end 0.8 -0.4)
      (stroke (width 0.15) (type solid)) (fill none) (layer "B.Fab"))
    (pad "1" smd roundrect (at -0.7 0 90) (size 0.6 0.8) (layers "B.Cu" "B.Paste" "B.Mask") (roundrect_rratio 0.2)
      (net 11 "GND") (pintype "passive"))
    (pad "2" smd roundrect (at 0.7 0 90) (size 0.6 0.8) (layers "B.Cu" "B.Paste" "B.Mask") (roundrect_rratio 0.2)
      (net 170 "3V3_SSD") (pintype "passive"))
  )
	(footprint "scalenode-cm4-baseboard-footprints:C_0805_2012Metric" (layer "B.Cu")
    (at 121.6 87.8)
    (descr "Capacitor SMD 0805")
    (tags "capacitor SMD 0805")
    (property "Author" "Antmicro")
    (property "Dielectric" "")
    (property "License" "Apache-2.0")
    (property "MPN" "0805ZD226MAT2A")
    (property "Manufacturer" "AVX")
    (property "Sheetfile" "supply.kicad_sch")
    (property "Sheetname" "Supply")
    (property "Val" "22u")
    (property "Voltage" "")
    (property "ki_description" " ")
    (attr smd)
    (fp_text reference "C19" (at -1.125 1.825) (layer "B.SilkS")
        (effects (font (size 0.7 0.7) (thickness 0.15)) (justify right bottom mirror))
    )
    (fp_text value "C_22u_0805_10V" (at 0 -1.947) (layer "B.Fab")
        (effects (font (size 0.7 0.7) (thickness 0.15)) (justify right bottom mirror))
    )
    (fp_text user "${REFERENCE}" (at -1.9 -3.947) (layer "B.Fab") hide
        (effects (font (size 0.7 0.7) (thickness 0.15)) (justify right bottom mirror))
    )
    (fp_text user "Author: Antmicro" (at -1.9 -5.947) (layer "B.Fab") hide
        (effects (font (size 0.7 0.7) (thickness 0.15)) (justify right bottom mirror))
    )
    (fp_text user "License: Apache-2.0" (at -1.9 -4.947) (layer "B.Fab") hide
        (effects (font (size 0.7 0.7) (thickness 0.15)) (justify right bottom mirror))
    )
    (fp_line (start -0.3 -0.8) (end 0.3 -0.8)
      (stroke (width 0.15) (type solid)) (layer "B.SilkS"))
    (fp_line (start -0.3 0.8) (end 0.3 0.8)
      (stroke (width 0.15) (type solid)) (layer "B.SilkS"))
    (fp_rect (start -1.9 0.93) (end 1.9 -0.93)
      (stroke (width 0.05) (type solid)) (fill none) (layer "B.CrtYd"))
    (fp_rect (start -0.95 0.675) (end 0.95 -0.675)
      (stroke (width 0.15) (type solid)) (fill none) (layer "B.Fab"))
    (pad "1" smd rect (at -1.05 0) (size 1.2 1.2) (layers "B.Cu" "B.Paste" "B.Mask")
      (net 11 "GND") (pintype "passive"))
    (pad "2" smd rect (at 1.05 0) (size 1.2 1.2) (layers "B.Cu" "B.Paste" "B.Mask")
      (net 170 "3V3_SSD") (pintype "passive"))
  )
)
